# S9S_MB_2U (Grand Teton) — schematic parts with pin connectivity, parts 4107–4255 of 6093; source: Cadence DE-HDL packaged netlist (pstxprt.dat, pstxnet.dat, pstchip.dat)

R1520  Q_RES  33.2 1% CHIP  pkg 0402LF  page 223 : 1 = RST_PCIE_CPU1_DEV_PERST_N ; 2 = RST_OCP_V3_2_N
R1525  Q_RES  0 5% CHIP  pkg 0402LF  page 241 : 1 = SMB_HOST_3V3AUX_SCL_R ; 2 = SMB_HOST_CLK_3V3AUX_SCL
R1526  Q_RES  33.2 1% CHIP  pkg 0402LF  page 241 : 1 = SMB_HOST_3V3AUX_SDA_R ; 2 = SMB_HOST_CLK_3V3AUX_SDA
R1527  Q_RES  1K 1% CHIP  pkg 0402LF  page 208 : 1 = FM_CLK_GEN1_OE0_N ; 2 = GND
R1541  Q_RES  100K 1% CHIP  pkg 0402LF  page 223 : 1 = GND ; 2 = RST_PLTRST_N
R1543  Q_RES  0 5% CHIP  pkg 0402LF  page 206 : 1 = OCP_SFF_CLK_OE_N ; 2 = FM_DB2000_9_OE_N
R1545  Q_RES  2K 1% CHIP  pkg 0402LF  page 183 : 1 = SMB_SML0B_3V3AUX_SCL ; 2 = P3V3_AUX
R1546  Q_RES  2K 1% CHIP  pkg 0402LF  page 183 : 1 = SMB_SML0B_3V3AUX_SDA ; 2 = P3V3_AUX
R1547  Q_RES  0 5% CHIP  pkg 0402LF  page 213 : 1 = FM_TPM_PRSNT_R_N ; 2 = FM_TPM_PRSNT_N
R1551  Q_RES  4.7K 1% EMPTY  pkg 0402LF  page 213 : 1 = P3V3_AUX ; 2 = SMB_1_PLD_3V3AUX_SDA_R1
R1554  Q_RES  10K 1% CHIP  pkg 0402LF  page 204 : 1 = P3V3_AUX ; 2 = FM_ME_AUTHN_FAIL
R1558  Q_RES  10K 1% EMPTY  pkg 0402LF  page 220 : 1 = FM_CPU_RMCA_CATERR_LVT3_R_N ; 2 = P3V3_AUX
R1571  Q_RES  100K 1% CHIP  pkg 0402LF  page 259 : 1 = MB0_P12V_STBY_PWRGD ; 2 = P3V3_AUX_EN
R1581  Q_RES  2K 1% CHIP  pkg 0402LF  page 183 : 1 = PU_SMB_PCH_PLD_3V3AUX_SCL ; 2 = P3V3_AUX
R1582  Q_RES  2K 1% CHIP  pkg 0402LF  page 183 : 1 = PU_SMB_PCH_PLD_3V3AUX_SDA ; 2 = P3V3_AUX
R1583  Q_RES  10K 1% CHIP  pkg 0402LF  page 183 : 1 = PU_PCH_PLD_3V3AUX_ALERT_N ; 2 = P3V3_AUX
R1592  Q_RES  10K 1% CHIP  pkg 0402LF  page 155 : 1 = P3V3_OCP_SFF ; 2 = PU_OCP_SFF_WAKE_OE
R1593  Q_RES  4.7K 1% CHIP  pkg 0402LF  page 155 : 1 = P3V3_AUX ; 2 = OCP_SFF_PWRBRK_BUFF_N
R1594  Q_RES  33.2 1% CHIP  pkg 0402LF  page 155 : 1 = OCP_SFF_WAKE_BUFF_N ; 2 = OCP_SFF_WAKE_BUFF_R_N
R1595  Q_RES  33.2 1% CHIP  pkg 0402LF  page 155 : 1 = OCP_SFF_PWRBRK_BUFF_N ; 2 = OCP_SFF_PWRBRK_N
R1600  Q_RES  33.2 1% CHIP  pkg 0402LF  page 183 : 1 = IRQ_SML0_ALERT_N ; 2 = IRQ_SML0_ALERT_R_N
R1601  Q_RES  10K 1% CHIP  pkg 0402LF  page 183 : 1 = IRQ_SML0_ALERT_N ; 2 = P3V3_AUX
R1605  Q_RES  1K 1% CHIP  pkg 0402LF  page 190 : 1 = PD_M2_0_DEVSLP ; 2 = GND
R1606  Q_RES  33.2 1% CHIP  pkg 0402LF  page 213 : 1 = FM_OCP_SFF_PWR_GOOD ; 2 = FM_OCP_SFF_PWR_GOOD_R
R1607  Q_RES  0 5% EMPTY  pkg 0402LF  page 260 : 1 = FM_PS_EN_PLD_R ; 2 = VR_P5V_EN
R1640  Q_RES  0 5% CHIP  pkg 0402LF  page 260 : 1 = FM_P5V_EN ; 2 = VR_P5V_EN
R1641  Q_RES  100K 1% CHIP  pkg 0402LF  page 260 : 1 = VR_P5V_EN ; 2 = GND
R1642  Q_RES  10K 1% CHIP  pkg 0402LF  page 260 : 1 = P12V_AUX ; 2 = VR_P5V_EN_D_R
R1643  Q_RES  100K 1% CHIP  pkg 0402LF  page 260 : 1 = P12V_AUX ; 2 = VR_P5V_EN_N
R1648  Q_RES  0 5% EMPTY  pkg 0402LF  page 236 : 1 = SMB_S3M_CPU0_3V3AUX_SDA ; 2 = SMB_S3M_CPU1_3V3AUX_SDA
R1650  Q_RES  0 5% CHIP  pkg 0402LF  page 262 : 1 = PWRGD_P1V05_PCH_AUX_R ; 2 = PWRGD_P1V05_PCH_AUX
R1652  Q_RES  0 5% CHIP  pkg 0402LF  page 282 : 1 = PWRGD_PVNN_MAIN_CPU0_R ; 2 = PWRGD_PVNN_MAIN_CPU0
R1654  Q_RES  1K 1% CHIP  pkg 0402LF  page 260 : 1 = VR_P5V_EN_D_R ; 2 = VR_P5V_EN_D_R1
R1655  Q_RES  10K 1% CHIP  pkg 0402LF  page 260 : 1 = P12V_AUX ; 2 = PWRGD_P5V_ISO_R
R1656  Q_RES  33.2 1% CHIP  pkg 0402LF  page 183 : 1 = IRQ_SML1_PMBUS_ALERT_N ; 2 = IRQ_SML1_PMBUS_PLD_ALERT_N
R1657  Q_RES  33.2 1% CHIP  pkg 0402LF  page 183 : 1 = IRQ_SML1_PMBUS_ALERT_N ; 2 = IRQ_SML1_PMBUS_BMC_ALERT_N
R1659  Q_RES  10K 1% CHIP  pkg 0402LF  page 183 : 1 = FM_PMBUS_ALERT_B_EN ; 2 = P3V3_AUX
R1660  Q_RES  10K 1% EMPTY  pkg 0402LF  page 220 : 1 = FM_SLP_SUS_RSM_RST_N ; 2 = P3V3_AUX
R1661  Q_RES  33.2 1% CHIP  pkg 0402LF  page 241 : 1 = SMB_VR_3V3AUX_SCL ; 2 = SMB_VR_3V3AUX_SCL_R
R1662  Q_RES  33.2 1% CHIP  pkg 0402LF  page 241 : 1 = SMB_VR_3V3AUX_SDA ; 2 = SMB_VR_3V3AUX_SDA_R
R1671  Q_RES  0 5% CHIP  pkg 0402LF  page 153 : 1 = OCP_SFF_AUX_PWR_EN ; 2 = OCP_SFF_AUX_PWR_EN_R
R1673  Q_RES  10K 1% CHIP  pkg 0402LF  page 191 : 1 = P3V3_E1S_0 ; 2 = RST_SMB_E1S_0_N
R1675  Q_RES  2.49K 1% CHIP  pkg 0402LF  page 182 : 1 = FM_PCIE_EV_BIF_EN ; 2 = P3V3_AUX
R1676  Q_RES  1K 1% EMPTY  pkg 0402LF  page 182 : 1 = FM_PCIE_EV_BIF_EN ; 2 = GND
R1680  Q_RES  0 5% CHIP  pkg 0402LF  page 208 : 1 = FM_PLD_CLK_25M_EN ; 2 = FM_CK440Q_DEV_25M_EN
R1681  Q_RES  10K 1% CHIP  pkg 0402LF  page 213 : 1 = P3V3_AUX ; 2 = PU_RST_DEDI_BUSY_PLD_N
R1688  Q_RES  100K 1% CHIP  pkg 0402LF  page 244 : 1 = P12V_AUX ; 2 = FM_COMP_P3V3_AUX_VIN
R1689  Q_RES  6.19K 1% CHIP  pkg 0402LF  page 244 : 1 = FM_COMP_P3V3_AUX_VIN ; 2 = GND
R1690  Q_RES  10K 1% CHIP  pkg 0402LF  page 244 : 1 = P3V3_AUX ; 2 = FM_COMP_P3V3_AUX_ENIN
R1691  Q_RES  10K 1% EMPTY  pkg 0402LF  page 244 : 1 = P3V3_AUX ; 2 = PWRGD_DSW_PWROK_R1
R1692  Q_RES  100K 1% CHIP  pkg 0402LF  page 244 : 1 = PWRGD_DSW_PWROK_R1 ; 2 = GND
R1693  Q_RES  33.2 1% CHIP  pkg 0402LF  page 244 : 1 = PWRGD_DSW_PWROK_R2 ; 2 = PWRGD_DSW_PWROK
R1694  Q_RES  10K 1% CHIP  pkg 0402LF  page 244 : 1 = P3V3_AUX ; 2 = PWRGD_DSW_PWROK
R1695  Q_RES  0 5% EMPTY  pkg 0402LF  page 244 : 1 = PWRGD_DSW_PWROK ; 2 = RST_RSMRST_PCH_N
R1700  Q_RES  200K 1% CHIP  pkg 0402LF  page 194 : 1 = P3V3_AUX ; 2 = SMB_PCIE_M2_0_EN
R1702  Q_RES  4.7K 5% CHIP  pkg 0402LF  page 194 : 1 = P1V8_PCH_AUX ; 2 = SMB_M2_P0_1V8AUX_SDA_R
R1703  Q_RES  4.7K 5% CHIP  pkg 0402LF  page 194 : 1 = P1V8_PCH_AUX ; 2 = SMB_M2_P0_1V8AUX_SCL_R
R1706  Q_RES  10K 1% EMPTY  pkg 0402LF  page 260 : 1 = P3V3 ; 2 = PWRGD_P3V3_R1
R1710  Q_RES  49.9 1% CHIP  pkg 0402LF  page 215 : 1 = FM_PLD_REV_N ; 2 = FM_PLD_REV_R_N
R1712  Q_RES  4.7K 5% EMPTY  pkg 0402LF  page 266 : 1 = SMB_VR_3V3AUX_SDA_R3 ; 2 = P3V3_AUX
R1713  Q_RES  4.7K 5% EMPTY  pkg 0402LF  page 266 : 1 = SMB_VR_3V3AUX_SCL_R3 ; 2 = P3V3_AUX
R1714  Q_RES  0 5% CHIP  pkg 0402LF  page 301 : 1 = SMB_SML1_PMBUS_HSC_SDA ; 2 = SMB_SML1_PMBUS_HSC_R_SDA
R1717  Q_RES  49.9 1% CHIP  pkg 0402LF  page 278 : 1 = PVNN_TERM_CPU0 ; 2 = SVID_CLK1_CPU0_R
R1718  Q_RES  49.9 1% CHIP  pkg 0402LF  page 296 : 1 = PVNN_TERM_CPU1 ; 2 = SVID_CLK1_CPU1_R
R1719  Q_RES  33.2 1% CHIP  pkg 0402LF  page 154 : 1 = OCP_SFF_AUX_PWR_EN ; 2 = OCP_SFF_AUX_PWR_EN_R1
R1720  Q_RES  0 5% EMPTY  pkg 0402LF  page 179 : 1 = XTAL_PCH_25M_IN_R ; 2 = XTAL_PCH_25M_IN
R1721  Q_RES  0 5% CHIP  pkg 0402LF  page 179 : 1 = XTAL_PCH_RTC2_R ; 2 = XTAL_PCH_RTC2
R1724  Q_RES  0 5% CHIP  pkg 0402LF  page 208 : 1 = XTAL_CLK_GEN1_25M_X1_R ; 2 = XTAL_CLK_GEN1_25M_X1
R1735  Q_RES  100 1% CHIP  pkg 0402LF  page 278 : 1 = PVNN_TERM_CPU0 ; 2 = SVID_DIO1_CPU0_R
R1736  Q_RES  33.2 1% CHIP  pkg 0402LF  page 182 : 1 = FM_PCH_SLP_SUS_N ; 2 = FM_SLP_SUS_RSM_RST_N
R1741  Q_RES  1K 1% CHIP  pkg 0402LF  page 220 : 1 = FM_RST_PERST_BIT0 ; 2 = P3V3_AUX
R1742  Q_RES  10K 1% EMPTY  pkg 0402LF  page 220 : 1 = FM_RST_PERST_BIT0 ; 2 = GND
R1744  Q_RES  0 5% CHIP  pkg 0402LF  page 223 : 1 = FM_BMC_PWRBTN_OUT_N ; 2 = FM_BMC_PWRBTN_N
R1745  Q_RES  0 5% EMPTY  pkg 0402LF  page 244 : 1 = FM_COMP_P3V3_AUX_ENIN ; 2 = FM_PFR_DSW_PWROK_N
R1747  Q_RES  0 5% CHIP  pkg 0805LF  page 257 : 1 = P1V8_PCH_AUX ; 2 = PGPPA_AUX
R1748  Q_RES  0 5% CHIP  pkg 0402LF  page 202 : 1 = FM_ESPI_PLD_EN ; 2 = FM_ESPI_PLD_R_EN_BUF
R1749  Q_RES  10K 1% EMPTY  pkg 0402LF  page 202 : 1 = FM_ESPI_PLD_R1_EN ; 2 = GND
R1750  Q_RES  1K 1% CHIP  pkg 0402LF  page 202 : 1 = PGPPA_AUX ; 2 = FM_ESPI_PLD_R_EN_BUF
R1751  Q_RES  33.2 1% CHIP  pkg 0402LF  page 222 : 1 = SGPIO_DO_0 ; 2 = SGPIO_DEBUG_PLD_DOUT
R1752  Q_RES  33.2 1% CHIP  pkg 0402LF  page 222 : 1 = SGPIO_CLK_0 ; 2 = SGPIO_DEBUG_PLD_CLK
R1753  Q_RES  33.2 1% CHIP  pkg 0402LF  page 222 : 1 = SGPIO_DI_0 ; 2 = SGPIO_DEBUG_PLD_DIN
R1754  Q_RES  33.2 1% CHIP  pkg 0402LF  page 222 : 1 = SGPIO_LD_0 ; 2 = SGPIO_DEBUG_PLD_LD_N
R1755  Q_RES  33.2 1% CHIP  pkg 0402LF  page 222 : 1 = SGPIO_DO_1 ; 2 = SGPIO_BMC_DOUT
R1756  Q_RES  33.2 1% CHIP  pkg 0402LF  page 222 : 1 = SGPIO_CLK_1 ; 2 = SGPIO_BMC_CLK
R1757  Q_RES  33.2 1% CHIP  pkg 0402LF  page 222 : 1 = SGPIO_DI_1 ; 2 = SGPIO_BMC_DIN_R
R1758  Q_RES  33.2 1% CHIP  pkg 0402LF  page 222 : 1 = SGPIO_LD_1 ; 2 = SGPIO_BMC_LD_N
R1763  Q_RES  10K 1% EMPTY  pkg 0402LF  page 257 : 1 = PGPPA_AUX ; 2 = FM_LPC_ESPI_SEL
R1764  Q_RES  1K 1% EMPTY  pkg 0402LF  page 257 : 1 = FM_LPC_ESPI_SEL ; 2 = GND
R1765  Q_RES  0 5% EMPTY  pkg 0805LF  page 257 : 1 = PGPPA_AUX ; 2 = P3V3_AUX
R1785  Q_RES  4.7K 1% CHIP  pkg 0402LF  page 250 : 1 = P3V3_AUX_ADC ; 2 = GND
R1791  Q_RES  9.09K 1% CHIP  pkg 0402LF  page 250 : 1 = P5V_ADC ; 2 = GND
R1792  Q_RES  0 5% EMPTY  pkg 0402LF  page 250 : 1 = SMB_VR_3V3AUX_SDA_R1 ; 2 = SMB_SEN_MAM_3V3AUX_SDA
R1793  Q_RES  0 5% EMPTY  pkg 0402LF  page 250 : 1 = SMB_VR_3V3AUX_SCL_R1 ; 2 = SMB_SEN_MAM_3V3AUX_SCL
R1798  Q_RES  0 5% CHIP  pkg 0402LF  page 240 : 1 = ROT_P1_RST_IND_N_R ; 2 = ROT_P1_RST_IND_N
R1799  Q_RES  7.87K 1% CHIP  pkg 0402LF  page 250 : 1 = P12V_AUX ; 2 = P12V_AUX_ADC
R1800  Q_RES  1.21K 1% CHIP  pkg 0402LF  page 250 : 1 = P12V_AUX_ADC ; 2 = GND
R1801  Q_RES  0 5% CHIP  pkg 0402LF  page 240 : 1 = PRSNT0_N ; 2 = GND
R1809  Q_RES  20K 1% CHIP  pkg 0402LF  page 198 : 1 = P3V3_AUX ; 2 = FM_ADR_MODE0
R1810  Q_RES  1K 1% EMPTY  pkg 0402LF  page 198 : 1 = FM_ADR_MODE0 ; 2 = GND
R1811  Q_RES  33.2 1% CHIP  pkg 0402LF  page 222 : 1 = RST_SGPIO_RESET_N ; 2 = RST_SGPIO_RESET_N_R
R1812  Q_RES  33.2 1% CHIP  pkg 0402LF  page 222 : 1 = IRQ_SGPIO_INTR_N ; 2 = IRQ_SGPIO_INTR_N_R
R1813  Q_RES  10K 1% EMPTY  pkg 0402LF  page 239 : 1 = P3V3_AUX ; 2 = FM_JTAG_BMC_MUX_SEL
R1814  Q_RES  1K 1% EMPTY  pkg 0402LF  page 239 : 1 = FM_JTAG_BMC_MUX_SEL ; 2 = GND
R1815  Q_RES  0 5% CHIP  pkg 0402LF  page 240 : 1 = FM_BMC_PWRBTN_OUT_N ; 2 = FM_BMC_PWRBTN_OUT_R_N
R1816  Q_RES  0 5% CHIP  pkg 0402LF  page 240 : 1 = PWRGD_PS_PWROK ; 2 = PWRGD_PS_PWROK_R
R1820  Q_RES  10K 1% CHIP  pkg 0402LF  page 203 : 1 = P3V3_AUX ; 2 = FM_PLT_BMC_THERMTRIP_R_N
R1821  Q_RES  200 1% CHIP  pkg 0402LF  page 229 : 1 = FM_SPD_REMOTE_EN_R ; 2 = FM_SPD_REMOTE_EN
R1822  Q_RES  10K 1% CHIP  pkg 0402LF  page 231 : 1 = P3V3_AUX ; 2 = RST_SMB_SWITCH_N
R1823  Q_RES  1K 1% CHIP  pkg 0402LF  page 216 : 1 = P3V3_AUX ; 2 = RST_MB_STBY_R_N
R1824  Q_RES  10K 1% CHIP  pkg 0402LF  page 155 : 1 = P3V3_OCP_SFF ; 2 = IRQ_LVC3_OCP_SFF_WAKE_N
R1827  Q_RES  33.2 1% CHIP  pkg 0402LF  page 183 : 1 = USB_OC1_REAR_R_N ; 2 = USB_OC1_REAR_N
R1828  Q_RES  10K 1% CHIP  pkg 0402LF  page 183 : 1 = USB_OC1_REAR_R_N ; 2 = P3V3_AUX
R1831  Q_RES  0 5% EMPTY  pkg 0402LF  page 239 : 1 = JTAG_DBP_BMC_PRDY_N ; 2 = JTAG_DBP_BMC_PRDY_R_N
R1832  Q_RES  0 5% EMPTY  pkg 0402LF  page 239 : 1 = JTAG_BMC_DBP_PREQ_N ; 2 = JTAG_DBP_BMC_PREQ_R_N
R1833  Q_RES  0 5% EMPTY  pkg 0402LF  page 214 : 1 = FM_JTAG_BMC_MUX_SEL_R ; 2 = FM_JTAG_BMC_MUX_SEL

R1837  Q_RES_4P_12  0.001 1% CHIP  pkg R2512_4P_H41  page 251
  1  \1\  UNSPEC  = P12V_AUX
  2  \2\  UNSPEC  = P12V_S3_AUX_CPU1_NVDIMM
  3  \3\  UNSPEC  = P12V_AUX_CPU1_DIMM_ISEN_P
  4  \4\  UNSPEC  = P12V_AUX_CPU1_DIMM_ISEN_N

R1838  Q_RES_4P_12  0.001 1% CHIP  pkg R2512_4P_H41  page 251
  1  \1\  UNSPEC  = P12V_AUX
  2  \2\  UNSPEC  = P12V_S3_AUX_CPU0_NVDIMM
  3  \3\  UNSPEC  = P12V_AUX_CPU0_DIMM_ISEN_P
  4  \4\  UNSPEC  = P12V_AUX_CPU0_DIMM_ISEN_N

R1839  Q_RES  0 5% EMPTY  pkg 0402LF  page 185 : 1 = RST_PFR_OVR_RTC ; 2 = RST_RTCRST_N
R1840  Q_RES  0 5% EMPTY  pkg 0402LF  page 185 : 1 = RST_PFR_OVR_SRTC ; 2 = RST_SRTCRST_N
R1841  Q_RES  10K 1% CHIP  pkg 0402LF  page 218 : 1 = P3V3_AUX ; 2 = FM_CPU_RMCA_CATERR_LVT3_R_N
R1843  Q_RES  33.2 1% CHIP  pkg 0402LF  page 222 : 1 = RST_PFR_OVR_RTC_R ; 2 = RST_PFR_OVR_RTC
R1844  Q_RES  33.2 1% CHIP  pkg 0402LF  page 222 : 1 = RST_PFR_OVR_SRTC_R ; 2 = RST_PFR_OVR_SRTC
R1853  Q_RES  0 5% CHIP  pkg 0402LF  page 213 : 1 = VIRTUAL_RESEAT_FPGA_R_N ; 2 = VIRTUAL_RESEAT_FPGA_N
R1854  Q_RES  10K 1% CHIP  pkg 0402LF  page 242 : 1 = P3V3_AUX ; 2 = FM_SCM_PRSNT1_N
R1856  Q_RES  100 1% CHIP  pkg 0402LF  page 242 : 1 = FM_SCM_PRSNT1_N ; 2 = FM_SCM_PRSNT1_R_N
R1857  Q_RES  10K 1% CHIP  pkg 0402LF  page 242 : 1 = P3V3_AUX ; 2 = P12V_SCM_EN
R1868  Q_RES  10 1% CHIP  pkg 0402LF  page 202 : 1 = ESPI_LAD0_DATA_IO3 ; 2 = ESPI_LPC_LAD0_IO3
R1869  Q_RES  10 1% CHIP  pkg 0402LF  page 202 : 1 = ESPI_LAD0_DATA_IO2 ; 2 = ESPI_LPC_LAD0_IO2
R1870  Q_RES  10 1% CHIP  pkg 0402LF  page 202 : 1 = ESPI_LAD0_DATA_IO1 ; 2 = ESPI_LPC_LAD0_IO1
R1871  Q_RES  10 1% CHIP  pkg 0402LF  page 202 : 1 = ESPI_LAD0_DATA_IO0 ; 2 = ESPI_LPC_LAD0_IO0
R1872  Q_RES  10 1% CHIP  pkg 0402LF  page 202 : 1 = CLK_24M_66M_LPC0_ESPI ; 2 = ESPI_HOST_LPC_BMC_CLK
R1895  Q_RES  100 1% CHIP  pkg 0402LF  page 153 : 1 = OCP_SFF_PRSNTA_R_N ; 2 = GND
R1896  Q_RES  100 1% CHIP  pkg 0402LF  page 154 : 1 = OCP_SFF_ISO_BIF0_EN ; 2 = GND
R1897  Q_RES  100 1% CHIP  pkg 0402LF  page 154 : 1 = OCP_SFF_ISO_BIF1_EN ; 2 = GND
R1898  Q_RES  100 1% CHIP  pkg 0402LF  page 154 : 1 = OCP_SFF_ISO_BIF2_EN ; 2 = GND
R1905  Q_RES  1K 1% CHIP  pkg 0402LF  page 156 : 1 = P3V3_AUX ; 2 = OCP_SFF_PRSNT0_R_N
R1906  Q_RES  1K 1% CHIP  pkg 0402LF  page 156 : 1 = P3V3_AUX ; 2 = OCP_SFF_PRSNT2_R_N
R1907  Q_RES  1K 1% CHIP  pkg 0402LF  page 156 : 1 = P3V3_AUX ; 2 = OCP_SFF_PRSNT1_R_N
R1908  Q_RES  1K 1% CHIP  pkg 0402LF  page 156 : 1 = P3V3_AUX ; 2 = OCP_SFF_PRSNT3_R_N
R1919  Q_RES  33.2 1% CHIP  pkg 0402LF  page 222 : 1 = PWRGD_P3V3_AUX ; 2 = PWRGD_P3V3_AUX_PLD
R1921  Q_RES  33.2 1% CHIP  pkg 0402LF  page 158 : 1 = FM_SMB_CPU0_ALERT ; 2 = FM_SMB_PEHPCPU0_PCIE_ALERT_N
R1929  Q_RES  10K 1% CHIP  pkg 0402LF  page 153 : 1 = GND ; 2 = OCP_SFF_AUX_PWR_EN
R1930  Q_RES  10K 1% CHIP  pkg 0402LF  page 153 : 1 = GND ; 2 = OCP_SFF_MAIN_PWR_EN
R1932  Q_RES  33.2 1% CHIP  pkg 0402LF  page 14 : 1 = SMB_S3M_CPU0_PIROM_3V3AUX_SCL ; 2 = SMB_S3M_CPU0_PIROM_3V3AUX_SCL_1
R1933  Q_RES  33.2 1% CHIP  pkg 0402LF  page 14 : 1 = SMB_S3M_CPU0_PIROM_3V3AUX_SDA ; 2 = SMB_S3M_CPU0_PIROM_3V3AUX_SDA_1
R1934  Q_RES  33.2 1% CHIP  pkg 0402LF  page 45 : 1 = SMB_S3M_CPU1_PIROM_3V3AUX_SCL ; 2 = SMB_S3M_CPU1_PIROM_3V3AUX_SCL_1
R1935  Q_RES  33.2 1% CHIP  pkg 0402LF  page 45 : 1 = SMB_S3M_CPU1_PIROM_3V3AUX_SDA ; 2 = SMB_S3M_CPU1_PIROM_3V3AUX_SDA_1
R1944  Q_RES  0 5% CHIP  pkg 0402LF  page 215 : 1 = IRQ_PCH_SCI_WHEA_R_N ; 2 = IRQ_PCH_SCI_WHEA_N
R1950  Q_RES  0 5% CHIP  pkg 0402LF  page 244 : 1 = FM_COMP_P3V3_AUX_VIN ; 2 = FM_COMP_P3V3_AUX_VIN_R
